# T6G (Grand Teton) — schematic netlist excerpt (pin names and nets, part order shuffled) for the footprints in the layout excerpt that follows; sources: Cadence DE-HDL packaged netlist, KiCad conversion of 04192023_DAF0TMB3IC0_F0TG_MB_C_brd_V02_OCP.brd

R3195  Q_RES  0 5% CHIP  pkg 0402LF  page 55 : A = CLK_100M_CPU1_CLK02_R_DN ; B = CLK_100M_CPU1_CLK02_DN
H32  HOLE  EMPTY  pkg TH  page 230 : \1\ = GND
PC511  Q_CAP  0.1UF 25V 10% X7R  pkg 0402  page 225 : A = P12V_AUX ; B = GND

(kicad_pcb
	(version 20260206)
	(generator "pcbnew")
	(generator_version "10.0")
	(general
		(thickness 1.6)
		(legacy_teardrops no)
	)
	(paper "A4")
	(title_block
		(title "04192023_DAF0TMB3IC0_F0TG_MB_C_brd_V02_OCP.brd")
		(comment 1 "Grand Teton / footprints 1288-1290 of 8354")
	)
	(layers
		(0 "F.Cu" signal "TOP")
		(4 "In1.Cu" signal "GND")
		(6 "In2.Cu" signal "IN1")
		(8 "In3.Cu" signal "GND1")
		(10 "In4.Cu" signal "IN2")
		(12 "In5.Cu" signal "GND2")
		(14 "In6.Cu" signal "IN3")
		(16 "In7.Cu" signal "GND3")
		(18 "In8.Cu" signal "VCC")
		(20 "In9.Cu" signal "VCC1")
		(22 "In10.Cu" signal "GND4")
		(24 "In11.Cu" signal "IN4")
		(26 "In12.Cu" signal "GND5")
		(28 "In13.Cu" signal "IN5")
		(30 "In14.Cu" signal "GND6")
		(32 "In15.Cu" signal "IN6")
		(34 "In16.Cu" signal "GND7")
		(2 "B.Cu" signal "BOTTOM")
		(9 "F.Adhes" user "F.Adhesive")
		(11 "B.Adhes" user "B.Adhesive")
		(13 "F.Paste" user "Package Geometry/Pastemask Top")
		(15 "B.Paste" user "Package Geometry/Pastemask Bottom")
		(5 "F.SilkS" user "Ref Des/Silkscreen Top")
		(7 "B.SilkS" user "Ref Des/Silkscreen Bottom")
		(1 "F.Mask" user "Board Geometry/Soldermask Top")
		(3 "B.Mask" user "Board Geometry/Soldermask Bottom")
		(17 "Dwgs.User" user "User.Drawings")
		(19 "Cmts.User" user "User.Comments")
		(21 "Eco1.User" user "User.Eco1")
		(23 "Eco2.User" user "User.Eco2")
		(25 "Edge.Cuts" user "Board Geometry/Outline")
		(27 "Margin" user)
		(31 "F.CrtYd" user "Package Geometry/Place Bound Top")
		(29 "B.CrtYd" user "Package Geometry/Place Bound Bottom")
		(35 "F.Fab" user "Ref Des/Assembly Top")
		(33 "B.Fab" user "Ref Des/Assembly Bottom")
	)
	(footprint ""
		(layer "F.Cu")
		(at 156.322522 -191.361314 -90)
		(property "Reference" "R3195"
			(at 0 0 270)
			(layer "F.SilkS")
			(hide yes)
			(effects
				(font
					(size 1.27 1.27)
				)
			)
		)
		(property "Value" ""
			(at 0 0 270)
			(layer "F.Fab")
			(effects
				(font
					(size 1.27 1.27)
				)
			)
		)
		(duplicate_pad_numbers_are_jumpers no)
		(fp_line
			(start 0.353314 0.4064)
			(end -0.383286 0.4064)
			(stroke
				(width 0.1524)
				(type default)
			)
			(layer "F.SilkS")
		)
		(fp_line
			(start -0.7874 -0.014478)
			(end -0.7874 -0.4064)
			(stroke
				(width 0.1524)
				(type default)
			)
			(layer "F.SilkS")
		)
		(fp_line
			(start -0.7874 -0.4064)
			(end 0.7874 -0.4064)
			(stroke
				(width 0.1524)
				(type default)
			)
			(layer "F.SilkS")
		)
		(fp_line
			(start 0.7874 -0.4064)
			(end 0.7874 -0.014478)
			(stroke
				(width 0.1524)
				(type default)
			)
			(layer "F.SilkS")
		)
		(fp_line
			(start -0.67945 0.3048)
			(end -0.67945 -0.305054)
			(stroke
				(width 0.1)
				(type default)
			)
			(layer "F.Fab")
		)
		(fp_line
			(start -0.12065 0.3048)
			(end -0.67945 0.3048)
			(stroke
				(width 0.1)
				(type default)
			)
			(layer "F.Fab")
		)
		(fp_line
			(start 0.120396 0.3048)
			(end 0.120396 0.2794)
			(stroke
				(width 0.1)
				(type default)
			)
			(layer "F.Fab")
		)
		(fp_line
			(start 0.67945 0.3048)
			(end 0.120396 0.3048)
			(stroke
				(width 0.1)
				(type default)
			)
			(layer "F.Fab")
		)
		(fp_line
			(start -0.12065 0.2794)
			(end -0.12065 0.3048)
			(stroke
				(width 0.1)
				(type default)
			)
			(layer "F.Fab")
		)
		(fp_line
			(start 0.120396 0.2794)
			(end -0.12065 0.2794)
			(stroke
				(width 0.1)
				(type default)
			)
			(layer "F.Fab")
		)
		(fp_line
			(start -0.12065 -0.2794)
			(end 0.12065 -0.2794)
			(stroke
				(width 0.1)
				(type default)
			)
			(layer "F.Fab")
		)
		(fp_line
			(start 0.12065 -0.2794)
			(end 0.12065 -0.3048)
			(stroke
				(width 0.1)
				(type default)
			)
			(layer "F.Fab")
		)
		(fp_line
			(start 0.12065 -0.3048)
			(end 0.67945 -0.3048)
			(stroke
				(width 0.1)
				(type default)
			)
			(layer "F.Fab")
		)
		(fp_line
			(start 0.67945 -0.3048)
			(end 0.67945 0.3048)
			(stroke
				(width 0.1)
				(type default)
			)
			(layer "F.Fab")
		)
		(fp_line
			(start -0.67945 -0.305054)
			(end -0.12065 -0.305054)
			(stroke
				(width 0.1)
				(type default)
			)
			(layer "F.Fab")
		)
		(fp_line
			(start -0.12065 -0.305054)
			(end -0.12065 -0.2794)
			(stroke
				(width 0.1)
				(type default)
			)
			(layer "F.Fab")
		)
		(pad "1" smd circle
			(at -0.40005 0 270)
			(size 0 0)
			(layers "F.Cu" "F.Mask" "F.Paste")
			(net "CLK_100M_CPU1_CLK02_R_DN")
		)
		(pad "2" smd circle
			(at 0.40005 0 270)
			(size 0 0)
			(layers "F.Cu" "F.Mask" "F.Paste")
			(net "CLK_100M_CPU1_CLK02_DN")
		)
	)
	(footprint ""
		(layer "F.Cu")
		(at 100.382832 -47.049944)
		(property "Reference" "H32"
			(at -1.7272 -4.511548 0)
			(unlocked yes)
			(layer "B.SilkS")
			(effects
				(font
					(size 0.7874 0.5842)
					(thickness 0.1524)
				)
				(justify left mirror)
			)
		)
		(property "Value" ""
			(at 0 0 0)
			(layer "F.Fab")
			(effects
				(font
					(size 1.27 1.27)
				)
			)
		)
		(duplicate_pad_numbers_are_jumpers no)
		(pad "1" thru_hole circle
			(at 0 0)
			(size 4.5212 4.5212)
			(drill 3.81)
			(layers "*.Cu" "*.Mask")
			(remove_unused_layers no)
			(net "GND")
			(clearance -0.1016)
			(padstack
				(mode front_inner_back)
				(layer "Inner"
					(shape circle)
					(size 5.6134 5.6134)
					(clearance -0.6477)
				)
				(layer "B.Cu"
					(shape circle)
					(size 8.001 8.001)
					(clearance -1.8415)
				)
			)
		)
	)
	(footprint ""
		(layer "F.Cu")
		(at 180.395118 -365.058452 90)
		(property "Reference" "PC511"
			(at 0 0 90)
			(layer "F.SilkS")
			(hide yes)
			(effects
				(font
					(size 1.27 1.27)
				)
			)
		)
		(property "Value" ""
			(at 0 0 90)
			(layer "F.Fab")
			(effects
				(font
					(size 1.27 1.27)
				)
			)
		)
		(duplicate_pad_numbers_are_jumpers no)
		(fp_line
			(start 0.7874 -0.4064)
			(end 0.7874 0.4064)
			(stroke
				(width 0.1524)
				(type default)
			)
			(layer "F.SilkS")
		)
		(fp_line
			(start -0.7874 -0.4064)
			(end 0.7874 -0.4064)
			(stroke
				(width 0.1524)
				(type default)
			)
			(layer "F.SilkS")
		)
		(fp_line
			(start 0.7874 0.4064)
			(end -0.7874 0.4064)
			(stroke
				(width 0.1524)
				(type default)
			)
			(layer "F.SilkS")
		)
		(fp_line
			(start -0.7874 0.4064)
			(end -0.7874 -0.4064)
			(stroke
				(width 0.1524)
				(type default)
			)
			(layer "F.SilkS")
		)
		(fp_line
			(start -0.12065 -0.305054)
			(end -0.12065 -0.2794)
			(stroke
				(width 0.1)
				(type default)
			)
			(layer "F.Fab")
		)
		(fp_line
			(start -0.67945 -0.305054)
			(end -0.12065 -0.305054)
			(stroke
				(width 0.1)
				(type default)
			)
			(layer "F.Fab")
		)
		(fp_line
			(start 0.67945 -0.3048)
			(end 0.67945 0.3048)
			(stroke
				(width 0.1)
				(type default)
			)
			(layer "F.Fab")
		)
		(fp_line
			(start 0.12065 -0.3048)
			(end 0.67945 -0.3048)
			(stroke
				(width 0.1)
				(type default)
			)
			(layer "F.Fab")
		)
		(fp_line
			(start 0.12065 -0.2794)
			(end 0.12065 -0.3048)
			(stroke
				(width 0.1)
				(type default)
			)
			(layer "F.Fab")
		)
		(fp_line
			(start -0.12065 -0.2794)
			(end 0.12065 -0.2794)
			(stroke
				(width 0.1)
				(type default)
			)
			(layer "F.Fab")
		)
		(fp_line
			(start 0.120396 0.2794)
			(end -0.12065 0.2794)
			(stroke
				(width 0.1)
				(type default)
			)
			(layer "F.Fab")
		)
		(fp_line
			(start -0.12065 0.2794)
			(end -0.12065 0.3048)
			(stroke
				(width 0.1)
				(type default)
			)
			(layer "F.Fab")
		)
		(fp_line
			(start 0.67945 0.3048)
			(end 0.120396 0.3048)
			(stroke
				(width 0.1)
				(type default)
			)
			(layer "F.Fab")
		)
		(fp_line
			(start 0.120396 0.3048)
			(end 0.120396 0.2794)
			(stroke
				(width 0.1)
				(type default)
			)
			(layer "F.Fab")
		)
		(fp_line
			(start -0.12065 0.3048)
			(end -0.67945 0.3048)
			(stroke
				(width 0.1)
				(type default)
			)
			(layer "F.Fab")
		)
		(fp_line
			(start -0.67945 0.3048)
			(end -0.67945 -0.305054)
			(stroke
				(width 0.1)
				(type default)
			)
			(layer "F.Fab")
		)
		(pad "1" smd circle
			(at -0.40005 0 90)
			(size 0 0)
			(layers "F.Cu" "F.Mask" "F.Paste")
			(net "P12V_AUX")
		)
		(pad "2" smd circle
			(at 0.40005 0 90)
			(size 0 0)
			(layers "F.Cu" "F.Mask" "F.Paste")
			(net "GND")
		)
	)
)
